(kicad_pcb
	(version 20260206)
	(generator "pcbnew")
	(generator_version "10.0")
	(general
		(thickness 1.6)
		(legacy_teardrops no)
	)
	(paper "A4")
	(title_block
		(title "04192023_DAF0TMB3IC0_F0TG_MB_C_brd_V02_OCP.brd")
		(comment 1 "Grand Teton / footprint 655 of 8354 (U6013), pads 224-336 of 354")
	)
	(layers
		(0 "F.Cu" signal "TOP")
		(4 "In1.Cu" signal "GND")
		(6 "In2.Cu" signal "IN1")
		(8 "In3.Cu" signal "GND1")
		(10 "In4.Cu" signal "IN2")
		(12 "In5.Cu" signal "GND2")
		(14 "In6.Cu" signal "IN3")
		(16 "In7.Cu" signal "GND3")
		(18 "In8.Cu" signal "VCC")
		(20 "In9.Cu" signal "VCC1")
		(22 "In10.Cu" signal "GND4")
		(24 "In11.Cu" signal "IN4")
		(26 "In12.Cu" signal "GND5")
		(28 "In13.Cu" signal "IN5")
		(30 "In14.Cu" signal "GND6")
		(32 "In15.Cu" signal "IN6")
		(34 "In16.Cu" signal "GND7")
		(2 "B.Cu" signal "BOTTOM")
		(9 "F.Adhes" user "F.Adhesive")
		(11 "B.Adhes" user "B.Adhesive")
		(13 "F.Paste" user "Package Geometry/Pastemask Top")
		(15 "B.Paste" user "Package Geometry/Pastemask Bottom")
		(5 "F.SilkS" user "Ref Des/Silkscreen Top")
		(7 "B.SilkS" user "Ref Des/Silkscreen Bottom")
		(1 "F.Mask" user "Board Geometry/Soldermask Top")
		(3 "B.Mask" user "Board Geometry/Soldermask Bottom")
		(17 "Dwgs.User" user "User.Drawings")
		(19 "Cmts.User" user "User.Comments")
		(21 "Eco1.User" user "User.Eco1")
		(23 "Eco2.User" user "User.Eco2")
		(25 "Edge.Cuts" user "Board Geometry/Outline")
		(27 "Margin" user)
		(31 "F.CrtYd" user "Package Geometry/Place Bound Top")
		(29 "B.CrtYd" user "Package Geometry/Place Bound Bottom")
		(35 "F.Fab" user "Ref Des/Assembly Top")
		(33 "B.Fab" user "Ref Des/Assembly Bottom")
	)
	(footprint ""
		(layer "F.Cu")
		(at 379.567948 -395.724634)
		(property "Reference" "U6013"
			(at -8.471916 -7.649972 0)
			(unlocked yes)
			(layer "F.SilkS")
			(effects
				(font
					(size 0.7874 0.5842)
					(thickness 0.1524)
				)
				(justify left)
			)
		)
		(property "Value" ""
			(at 0 0 0)
			(layer "F.Fab")
			(effects
				(font
					(size 1.27 1.27)
				)
			)
		)
		(duplicate_pad_numbers_are_jumpers no)
		(pad "DY32" smd circle
			(at -5.997448 2.724912)
			(size 0.381 0.381)
			(layers "F.Cu" "F.Mask" "F.Paste")
			(net "GND")
		)
		(pad "E8" smd circle
			(at 10.366502 -1.988312)
			(size 0.3048 0.3048)
			(layers "F.Cu" "F.Mask" "F.Paste")
			(net "JTAG_TRST_RT_CPU0_P3_N")
		)
		(pad "E11" smd circle
			(at 10.366502 -1.388364)
			(size 0.3048 0.3048)
			(layers "F.Cu" "F.Mask" "F.Paste")
			(net "RXDET_BYP_RT_CPU0_P3")
		)
		(pad "E14" smd circle
			(at 10.366502 -0.788416)
			(size 0.3048 0.3048)
			(layers "F.Cu" "F.Mask" "F.Paste")
			(net "GND")
		)
		(pad "E18" smd circle
			(at 10.366502 -0.188468)
			(size 0.3048 0.3048)
			(layers "F.Cu" "F.Mask" "F.Paste")
			(net "Net_2214")
		)
		(pad "E27" smd circle
			(at 10.366502 1.61163)
			(size 0.3048 0.3048)
			(layers "F.Cu" "F.Mask" "F.Paste")
			(net "GND")
		)
		(pad "E30" smd circle
			(at 10.366502 2.211578)
			(size 0.3048 0.3048)
			(layers "F.Cu" "F.Mask" "F.Paste")
			(net "GND")
		)
		(pad "E33" smd circle
			(at 10.366502 2.811526)
			(size 0.3048 0.3048)
			(layers "F.Cu" "F.Mask" "F.Paste")
			(net "GND")
		)
		(pad "EA2" smd circle
			(at -6.050026 -3.41884)
			(size 0.3048 0.3048)
			(layers "F.Cu" "F.Mask" "F.Paste")
			(net "GND")
		)
		(pad "EA34" smd circle
			(at -6.050026 3.420364)
			(size 0.3048 0.3048)
			(layers "F.Cu" "F.Mask" "F.Paste")
			(net "GND")
		)
		(pad "EB1" smd oval
			(at -6.35 -3.938524)
			(size 0.254 0.3302)
			(layers "F.Cu" "F.Mask" "F.Paste")
			(net "GND")
		)
		(pad "EB35" smd oval
			(at -6.35 3.940048)
			(size 0.254 0.3302)
			(layers "F.Cu" "F.Mask" "F.Paste")
			(net "GND")
		)
		(pad "EC7" smd circle
			(at -6.397498 -2.12471)
			(size 0.381 0.381)
			(layers "F.Cu" "F.Mask" "F.Paste")
			(net "P5E_CPU0_P3_TX_BUF_DP<2>")
		)
		(pad "EC26" smd circle
			(at -6.397498 1.339342)
			(size 0.381 0.381)
			(layers "F.Cu" "F.Mask" "F.Paste")
			(net "P5E_CPU0_P3_RX_DP<2>")
		)
		(pad "ED2" smd circle
			(at -6.649974 -3.41884)
			(size 0.3048 0.3048)
			(layers "F.Cu" "F.Mask" "F.Paste")
			(net "P5E_CPU0_P3_RX_BUF_DN<2>")
		)
		(pad "ED34" smd circle
			(at -6.649974 3.420364)
			(size 0.3048 0.3048)
			(layers "F.Cu" "F.Mask" "F.Paste")
			(net "P5E_CPU0_P3_TX_C_DN<2>")
		)
		(pad "EE10" smd circle
			(at -6.797294 -1.431798)
			(size 0.381 0.381)
			(layers "F.Cu" "F.Mask" "F.Paste")
			(net "P5E_CPU0_P3_TX_BUF_DN<2>")
		)
		(pad "EE29" smd circle
			(at -6.797294 2.032254)
			(size 0.381 0.381)
			(layers "F.Cu" "F.Mask" "F.Paste")
			(net "P5E_CPU0_P3_RX_DN<2>")
		)
		(pad "EF1" smd oval
			(at -6.949948 -3.938524)
			(size 0.254 0.3302)
			(layers "F.Cu" "F.Mask" "F.Paste")
			(net "P5E_CPU0_P3_RX_BUF_DP<2>")
		)
		(pad "EF35" smd oval
			(at -6.949948 3.940048)
			(size 0.254 0.3302)
			(layers "F.Cu" "F.Mask" "F.Paste")
			(net "P5E_CPU0_P3_TX_C_DP<2>")
		)
		(pad "EG4" smd circle
			(at -7.197344 -2.817368)
			(size 0.381 0.381)
			(layers "F.Cu" "F.Mask" "F.Paste")
			(net "GND")
		)
		(pad "EG13" smd circle
			(at -7.197344 -0.79629)
			(size 0.3048 0.3048)
			(layers "F.Cu" "F.Mask" "F.Paste")
			(net "GND")
		)
		(pad "EG17" smd circle
			(at -7.197344 -0.296164)
			(size 0.3048 0.3048)
			(layers "F.Cu" "F.Mask" "F.Paste")
			(net "P0V9_CPU0_RT3_2A")
		)
		(pad "EG20" smd circle
			(at -7.197344 0.203708)
			(size 0.3048 0.3048)
			(layers "F.Cu" "F.Mask" "F.Paste")
			(net "P0V9_CPU0_RT3_2A")
		)
		(pad "EG22" smd circle
			(at -7.197344 0.703834)
			(size 0.3048 0.3048)
			(layers "F.Cu" "F.Mask" "F.Paste")
			(net "GND")
		)
		(pad "EG32" smd circle
			(at -7.197344 2.724912)
			(size 0.381 0.381)
			(layers "F.Cu" "F.Mask" "F.Paste")
			(net "GND")
		)
		(pad "EH2" smd circle
			(at -7.249922 -3.41884)
			(size 0.3048 0.3048)
			(layers "F.Cu" "F.Mask" "F.Paste")
			(net "GND")
		)
		(pad "EH34" smd circle
			(at -7.249922 3.420364)
			(size 0.3048 0.3048)
			(layers "F.Cu" "F.Mask" "F.Paste")
			(net "GND")
		)
		(pad "EJ1" smd oval
			(at -7.549896 -3.938524)
			(size 0.254 0.3302)
			(layers "F.Cu" "F.Mask" "F.Paste")
			(net "GND")
		)
		(pad "EJ35" smd oval
			(at -7.549896 3.940048)
			(size 0.254 0.3302)
			(layers "F.Cu" "F.Mask" "F.Paste")
			(net "GND")
		)
		(pad "EK7" smd circle
			(at -7.597394 -2.12471)
			(size 0.381 0.381)
			(layers "F.Cu" "F.Mask" "F.Paste")
			(net "P5E_CPU0_P3_TX_BUF_DP<1>")
		)
		(pad "EK26" smd circle
			(at -7.597394 1.339342)
			(size 0.381 0.381)
			(layers "F.Cu" "F.Mask" "F.Paste")
			(net "P5E_CPU0_P3_RX_DP<1>")
		)
		(pad "EL2" smd circle
			(at -7.850124 -3.41884)
			(size 0.3048 0.3048)
			(layers "F.Cu" "F.Mask" "F.Paste")
			(net "P5E_CPU0_P3_RX_BUF_DN<1>")
		)
		(pad "EL34" smd circle
			(at -7.850124 3.420364)
			(size 0.3048 0.3048)
			(layers "F.Cu" "F.Mask" "F.Paste")
			(net "P5E_CPU0_P3_TX_C_DP<1>")
		)
		(pad "EM10" smd circle
			(at -7.997444 -1.431798)
			(size 0.381 0.381)
			(layers "F.Cu" "F.Mask" "F.Paste")
			(net "P5E_CPU0_P3_TX_BUF_DN<1>")
		)
		(pad "EM29" smd circle
			(at -7.997444 2.032254)
			(size 0.381 0.381)
			(layers "F.Cu" "F.Mask" "F.Paste")
			(net "P5E_CPU0_P3_RX_DN<1>")
		)
		(pad "EN1" smd oval
			(at -8.150098 -3.938524)
			(size 0.254 0.3302)
			(layers "F.Cu" "F.Mask" "F.Paste")
			(net "P5E_CPU0_P3_RX_BUF_DP<1>")
		)
		(pad "EN35" smd oval
			(at -8.150098 3.940048)
			(size 0.254 0.3302)
			(layers "F.Cu" "F.Mask" "F.Paste")
			(net "P5E_CPU0_P3_TX_C_DN<1>")
		)
		(pad "EP4" smd circle
			(at -8.397494 -2.817368)
			(size 0.381 0.381)
			(layers "F.Cu" "F.Mask" "F.Paste")
			(net "GND")
		)
		(pad "EP13" smd circle
			(at -8.397494 -0.79629)
			(size 0.3048 0.3048)
			(layers "F.Cu" "F.Mask" "F.Paste")
			(net "GND")
		)
		(pad "EP17" smd circle
			(at -8.397494 -0.296164)
			(size 0.3048 0.3048)
			(layers "F.Cu" "F.Mask" "F.Paste")
			(net "P0V9_CPU0_RT3_2A")
		)
		(pad "EP20" smd circle
			(at -8.397494 0.203708)
			(size 0.3048 0.3048)
			(layers "F.Cu" "F.Mask" "F.Paste")
			(net "P0V9_CPU0_RT3_2A")
		)
		(pad "EP22" smd circle
			(at -8.397494 0.703834)
			(size 0.3048 0.3048)
			(layers "F.Cu" "F.Mask" "F.Paste")
			(net "GND")
		)
		(pad "EP32" smd circle
			(at -8.397494 2.724912)
			(size 0.381 0.381)
			(layers "F.Cu" "F.Mask" "F.Paste")
			(net "GND")
		)
		(pad "ER2" smd circle
			(at -8.450072 -3.41884)
			(size 0.3048 0.3048)
			(layers "F.Cu" "F.Mask" "F.Paste")
			(net "GND")
		)
		(pad "ER34" smd circle
			(at -8.450072 3.420364)
			(size 0.3048 0.3048)
			(layers "F.Cu" "F.Mask" "F.Paste")
			(net "GND")
		)
		(pad "ET1" smd oval
			(at -8.750046 -3.938524)
			(size 0.254 0.3302)
			(layers "F.Cu" "F.Mask" "F.Paste")
			(net "GND")
		)
		(pad "ET35" smd oval
			(at -8.750046 3.940048)
			(size 0.254 0.3302)
			(layers "F.Cu" "F.Mask" "F.Paste")
			(net "GND")
		)
		(pad "EU7" smd circle
			(at -8.79729 -2.12471)
			(size 0.381 0.381)
			(layers "F.Cu" "F.Mask" "F.Paste")
			(net "P5E_CPU0_P3_TX_BUF_DP<0>")
		)
		(pad "EU26" smd circle
			(at -8.79729 1.339342)
			(size 0.381 0.381)
			(layers "F.Cu" "F.Mask" "F.Paste")
			(net "P5E_CPU0_P3_RX_DP<0>")
		)
		(pad "EV2" smd circle
			(at -9.05002 -3.41884)
			(size 0.3048 0.3048)
			(layers "F.Cu" "F.Mask" "F.Paste")
			(net "P5E_CPU0_P3_RX_BUF_DN<0>")
		)
		(pad "EV34" smd circle
			(at -9.05002 3.420364)
			(size 0.3048 0.3048)
			(layers "F.Cu" "F.Mask" "F.Paste")
			(net "P5E_CPU0_P3_TX_C_DN<0>")
		)
		(pad "EW10" smd circle
			(at -9.19734 -1.431798)
			(size 0.381 0.381)
			(layers "F.Cu" "F.Mask" "F.Paste")
			(net "P5E_CPU0_P3_TX_BUF_DN<0>")
		)
		(pad "EW29" smd circle
			(at -9.19734 2.032254)
			(size 0.381 0.381)
			(layers "F.Cu" "F.Mask" "F.Paste")
			(net "P5E_CPU0_P3_RX_DN<0>")
		)
		(pad "EY1" smd oval
			(at -9.349994 -3.938524)
			(size 0.254 0.3302)
			(layers "F.Cu" "F.Mask" "F.Paste")
			(net "P5E_CPU0_P3_RX_BUF_DP<0>")
		)
		(pad "EY35" smd oval
			(at -9.349994 3.940048)
			(size 0.254 0.3302)
			(layers "F.Cu" "F.Mask" "F.Paste")
			(net "P5E_CPU0_P3_TX_C_DP<0>")
		)
		(pad "F2" smd circle
			(at 10.150094 -3.41884)
			(size 0.3048 0.3048)
			(layers "F.Cu" "F.Mask" "F.Paste")
			(net "RST_RT_CPU0_P3_PERST_N")
		)
		(pad "F34" smd circle
			(at 10.150094 3.420364)
			(size 0.3048 0.3048)
			(layers "F.Cu" "F.Mask" "F.Paste")
			(net "RT_CPU0_P3_ADDR1")
		)
		(pad "FA15" smd circle
			(at -9.59739 -0.738886)
			(size 0.381 0.381)
			(layers "F.Cu" "F.Mask" "F.Paste")
			(net "GND")
		)
		(pad "FA32" smd circle
			(at -9.59739 2.724912)
			(size 0.381 0.381)
			(layers "F.Cu" "F.Mask" "F.Paste")
			(net "GND")
		)
		(pad "FB2" smd circle
			(at -9.649968 -3.41884)
			(size 0.3048 0.3048)
			(layers "F.Cu" "F.Mask" "F.Paste")
			(net "GND")
		)
		(pad "FB34" smd circle
			(at -9.649968 3.420364)
			(size 0.3048 0.3048)
			(layers "F.Cu" "F.Mask" "F.Paste")
			(net "GND")
		)
		(pad "FC3" smd circle
			(at -9.846818 -2.888488)
			(size 0.3048 0.3048)
			(layers "F.Cu" "F.Mask" "F.Paste")
			(net "GND")
		)
		(pad "FC6" smd circle
			(at -9.846818 -2.288286)
			(size 0.3048 0.3048)
			(layers "F.Cu" "F.Mask" "F.Paste")
			(net "GND")
		)
		(pad "FC9" smd circle
			(at -9.846818 -1.688338)
			(size 0.3048 0.3048)
			(layers "F.Cu" "F.Mask" "F.Paste")
			(net "GND")
		)
		(pad "FC19" smd circle
			(at -9.846818 0.111506)
			(size 0.3048 0.3048)
			(layers "F.Cu" "F.Mask" "F.Paste")
			(net "GND")
		)
		(pad "FC23" smd circle
			(at -9.846818 0.711708)
			(size 0.3048 0.3048)
			(layers "F.Cu" "F.Mask" "F.Paste")
			(net "GND")
		)
		(pad "FC25" smd circle
			(at -9.846818 1.311656)
			(size 0.3048 0.3048)
			(layers "F.Cu" "F.Mask" "F.Paste")
			(net "GND")
		)
		(pad "FC28" smd circle
			(at -9.846818 1.911604)
			(size 0.3048 0.3048)
			(layers "F.Cu" "F.Mask" "F.Paste")
			(net "GND")
		)
		(pad "FD1" smd oval
			(at -9.949942 -3.938524)
			(size 0.254 0.3302)
			(layers "F.Cu" "F.Mask" "F.Paste")
			(net "GND")
		)
		(pad "FD35" smd oval
			(at -9.949942 3.940048)
			(size 0.254 0.3302)
			(layers "F.Cu" "F.Mask" "F.Paste")
			(net "GND")
		)
		(pad "FE2" smd circle
			(at -10.249916 -3.41884)
			(size 0.3048 0.3048)
			(layers "F.Cu" "F.Mask" "F.Paste")
			(net "NCF_CPU0_P3_GND")
		)
		(pad "FE34" smd circle
			(at -10.249916 3.420364)
			(size 0.3048 0.3048)
			(layers "F.Cu" "F.Mask" "F.Paste")
			(net "NCF_CPU0_P3_GND")
		)
		(pad "FF5" smd circle
			(at -10.366248 -2.588514)
			(size 0.3048 0.3048)
			(layers "F.Cu" "F.Mask" "F.Paste")
			(net "SMB_RT_CPU0_P3_ROM_MUX_1D_R_SCL")
		)
		(pad "FF8" smd circle
			(at -10.366248 -1.988312)
			(size 0.3048 0.3048)
			(layers "F.Cu" "F.Mask" "F.Paste")
			(net "JTAG_TEST_MODE_RT_CPU0_P3")
		)
		(pad "FF11" smd circle
			(at -10.366248 -1.388364)
			(size 0.3048 0.3048)
			(layers "F.Cu" "F.Mask" "F.Paste")
			(net "RST_RT_CPU0_P3_RESET_N")
		)
		(pad "FF14" smd circle
			(at -10.366248 -0.788416)
			(size 0.3048 0.3048)
			(layers "F.Cu" "F.Mask" "F.Paste")
			(net "GND")
		)
		(pad "FF18" smd circle
			(at -10.366248 -0.188468)
			(size 0.3048 0.3048)
			(layers "F.Cu" "F.Mask" "F.Paste")
			(net "CLK_100M_RETIMER_CPU0_P3_DN")
		)
		(pad "FF21" smd circle
			(at -10.366248 0.41148)
			(size 0.3048 0.3048)
			(layers "F.Cu" "F.Mask" "F.Paste")
			(net "GND")
		)
		(pad "FF24" smd circle
			(at -10.366248 1.011682)
			(size 0.3048 0.3048)
			(layers "F.Cu" "F.Mask" "F.Paste")
			(net "TEST0_RT_CPU0_P3")
		)
		(pad "FF27" smd circle
			(at -10.366248 1.61163)
			(size 0.3048 0.3048)
			(layers "F.Cu" "F.Mask" "F.Paste")
			(net "TEST1_RT_CPU0_P3")
		)
		(pad "FF30" smd circle
			(at -10.366248 2.211578)
			(size 0.3048 0.3048)
			(layers "F.Cu" "F.Mask" "F.Paste")
			(net "TEST2_RT_CPU0_P3")
		)
		(pad "FF33" smd circle
			(at -10.366248 2.811526)
			(size 0.3048 0.3048)
			(layers "F.Cu" "F.Mask" "F.Paste")
			(net "RT_CPU0_P3_SCAN_MODE")
		)
		(pad "FG1" smd oval
			(at -10.54989 -3.938524)
			(size 0.254 0.3302)
			(layers "F.Cu" "F.Mask" "F.Paste")
			(net "NCF_CPU0_P3_GND")
		)
		(pad "FG35" smd oval
			(at -10.54989 3.940048)
			(size 0.254 0.3302)
			(layers "F.Cu" "F.Mask" "F.Paste")
			(net "NCF_CPU0_P3_GND")
		)
		(pad "FH2" smd circle
			(at -10.850118 -3.41884)
			(size 0.3048 0.3048)
			(layers "F.Cu" "F.Mask" "F.Paste")
			(net "NCF_CPU0_P3_GND")
		)
		(pad "FH34" smd circle
			(at -10.850118 3.420364)
			(size 0.3048 0.3048)
			(layers "F.Cu" "F.Mask" "F.Paste")
			(net "NCF_CPU0_P3_GND")
		)
		(pad "FJ3" smd oval
			(at -10.885932 -2.888488 90)
			(size 0.254 0.3302)
			(layers "F.Cu" "F.Mask" "F.Paste")
			(net "SMB_RT_CPU0_P3_ROM_MUX_1D_R_SDA")
		)
		(pad "FJ6" smd oval
			(at -10.885932 -2.288286 90)
			(size 0.254 0.3302)
			(layers "F.Cu" "F.Mask" "F.Paste")
			(net "Net_2212")
		)
		(pad "FJ9" smd oval
			(at -10.885932 -1.688338 90)
			(size 0.254 0.3302)
			(layers "F.Cu" "F.Mask" "F.Paste")
			(net "MODE_RT_CPU0_P3")
		)
		(pad "FJ12" smd oval
			(at -10.885932 -1.08839 90)
			(size 0.254 0.3302)
			(layers "F.Cu" "F.Mask" "F.Paste")
			(net "GND")
		)
		(pad "FJ16" smd oval
			(at -10.885932 -0.488442 90)
			(size 0.254 0.3302)
			(layers "F.Cu" "F.Mask" "F.Paste")
			(net "CLK_100M_RETIMER_CPU0_P3_DP")
		)
		(pad "FJ19" smd oval
			(at -10.885932 0.111506 90)
			(size 0.254 0.3302)
			(layers "F.Cu" "F.Mask" "F.Paste")
			(net "GND")
		)
		(pad "FJ23" smd oval
			(at -10.885932 0.711708 90)
			(size 0.254 0.3302)
			(layers "F.Cu" "F.Mask" "F.Paste")
			(net "Net_2213")
		)
		(pad "FJ25" smd oval
			(at -10.885932 1.311656 90)
			(size 0.254 0.3302)
			(layers "F.Cu" "F.Mask" "F.Paste")
			(net "GPIO2_RT_CPU0_P3")
		)
		(pad "FJ28" smd oval
			(at -10.885932 1.911604 90)
			(size 0.254 0.3302)
			(layers "F.Cu" "F.Mask" "F.Paste")
			(net "GPIO3_RT_CPU0_P3")
		)
		(pad "FJ31" smd oval
			(at -10.885932 2.511552 90)
			(size 0.254 0.3302)
			(layers "F.Cu" "F.Mask" "F.Paste")
			(net "Net_53")
		)
		(pad "G1" smd oval
			(at 9.85012 -3.938524)
			(size 0.254 0.3302)
			(layers "F.Cu" "F.Mask" "F.Paste")
			(net "RT_CPU0_P3_VQPS")
		)
		(pad "G35" smd oval
			(at 9.85012 3.940048)
			(size 0.254 0.3302)
			(layers "F.Cu" "F.Mask" "F.Paste")
			(net "CLKREQ_RT_CPU0_P3_N")
		)
		(pad "H12" smd circle
			(at 9.846818 -1.08839)
			(size 0.3048 0.3048)
			(layers "F.Cu" "F.Mask" "F.Paste")
			(net "GND")
		)
		(pad "H16" smd circle
			(at 9.846818 -0.488442)
			(size 0.3048 0.3048)
			(layers "F.Cu" "F.Mask" "F.Paste")
			(net "GND")
		)
		(pad "H19" smd circle
			(at 9.846818 0.111506)
			(size 0.3048 0.3048)
			(layers "F.Cu" "F.Mask" "F.Paste")
			(net "GND")
		)
		(pad "H31" smd circle
			(at 9.846818 2.511552)
			(size 0.3048 0.3048)
			(layers "F.Cu" "F.Mask" "F.Paste")
			(net "GND")
		)
		(pad "J4" smd circle
			(at 9.602724 -2.817368)
			(size 0.381 0.381)
			(layers "F.Cu" "F.Mask" "F.Paste")
			(net "GND")
		)
		(pad "J22" smd circle
			(at 9.602724 0.703834)
			(size 0.3048 0.3048)
			(layers "F.Cu" "F.Mask" "F.Paste")
			(net "GND")
		)
		(pad "K2" smd circle
			(at 9.549892 -3.41884)
			(size 0.3048 0.3048)
			(layers "F.Cu" "F.Mask" "F.Paste")
			(net "GND")
		)
		(pad "K34" smd circle
			(at 9.549892 3.420364)
			(size 0.3048 0.3048)
			(layers "F.Cu" "F.Mask" "F.Paste")
			(net "GND")
		)
		(pad "L1" smd oval
			(at 9.249918 -3.938524)
			(size 0.254 0.3302)
			(layers "F.Cu" "F.Mask" "F.Paste")
			(net "GND")
		)
		(pad "L35" smd oval
			(at 9.249918 3.940048)
			(size 0.254 0.3302)
			(layers "F.Cu" "F.Mask" "F.Paste")
			(net "GND")
		)
		(pad "M7" smd circle
			(at 9.202674 -2.12471)
			(size 0.381 0.381)
			(layers "F.Cu" "F.Mask" "F.Paste")
			(net "P5E_CPU0_P3_TX_BUF_DP<15>")
		)
		(pad "M26" smd circle
			(at 9.202674 1.339342)
			(size 0.381 0.381)
			(layers "F.Cu" "F.Mask" "F.Paste")
			(net "P5E_CPU0_P3_RX_DP<15>")
		)
		(pad "N2" smd circle
			(at 8.949944 -3.41884)
			(size 0.3048 0.3048)
			(layers "F.Cu" "F.Mask" "F.Paste")
			(net "P5E_CPU0_P3_RX_BUF_DN<15>")
		)
		(pad "N34" smd circle
			(at 8.949944 3.420364)
			(size 0.3048 0.3048)
			(layers "F.Cu" "F.Mask" "F.Paste")
			(net "P5E_CPU0_P3_TX_C_DN<15>")
		)
	)
)
